# T6G (Grand Teton) — schematic netlist excerpt (pin names and nets, part order shuffled) for the footprints in the layout excerpt that follows; sources: Cadence DE-HDL packaged netlist, KiCad conversion of 04192023_DAF0TMB3IC0_F0TG_MB_C_brd_V02_OCP.brd

C996  Q_CAP  4.7UF 6.3V 20% X6S  pkg 0402  page 312 : A = P1V8_CPU0_RT3_1A ; B = GND
C3912  Q_CAP  22UF 4V 20% X6S  pkg C0402  page 74 : A = PVDDCR_SOC_P1 ; B = GND

(kicad_pcb
	(version 20260206)
	(generator "pcbnew")
	(generator_version "10.0")
	(general
		(thickness 1.6)
		(legacy_teardrops no)
	)
	(paper "A4")
	(title_block
		(title "04192023_DAF0TMB3IC0_F0TG_MB_C_brd_V02_OCP.brd")
		(comment 1 "Grand Teton / footprints 5305-5306 of 8354")
	)
	(layers
		(0 "F.Cu" signal "TOP")
		(4 "In1.Cu" signal "GND")
		(6 "In2.Cu" signal "IN1")
		(8 "In3.Cu" signal "GND1")
		(10 "In4.Cu" signal "IN2")
		(12 "In5.Cu" signal "GND2")
		(14 "In6.Cu" signal "IN3")
		(16 "In7.Cu" signal "GND3")
		(18 "In8.Cu" signal "VCC")
		(20 "In9.Cu" signal "VCC1")
		(22 "In10.Cu" signal "GND4")
		(24 "In11.Cu" signal "IN4")
		(26 "In12.Cu" signal "GND5")
		(28 "In13.Cu" signal "IN5")
		(30 "In14.Cu" signal "GND6")
		(32 "In15.Cu" signal "IN6")
		(34 "In16.Cu" signal "GND7")
		(2 "B.Cu" signal "BOTTOM")
		(9 "F.Adhes" user "F.Adhesive")
		(11 "B.Adhes" user "B.Adhesive")
		(13 "F.Paste" user "Package Geometry/Pastemask Top")
		(15 "B.Paste" user "Package Geometry/Pastemask Bottom")
		(5 "F.SilkS" user "Ref Des/Silkscreen Top")
		(7 "B.SilkS" user "Ref Des/Silkscreen Bottom")
		(1 "F.Mask" user "Board Geometry/Soldermask Top")
		(3 "B.Mask" user "Board Geometry/Soldermask Bottom")
		(17 "Dwgs.User" user "User.Drawings")
		(19 "Cmts.User" user "User.Comments")
		(21 "Eco1.User" user "User.Eco1")
		(23 "Eco2.User" user "User.Eco2")
		(25 "Edge.Cuts" user "Board Geometry/Outline")
		(27 "Margin" user)
		(31 "F.CrtYd" user "Package Geometry/Place Bound Top")
		(29 "B.CrtYd" user "Package Geometry/Place Bound Bottom")
		(35 "F.Fab" user "Ref Des/Assembly Top")
		(33 "B.Fab" user "Ref Des/Assembly Bottom")
	)
	(footprint ""
		(layer "B.Cu")
		(at 121.685812 -259.73024)
		(property "Reference" "C3912"
			(at 0 0 0)
			(layer "B.SilkS")
			(hide yes)
			(effects
				(font
					(size 1.27 1.27)
				)
				(justify mirror)
			)
		)
		(property "Value" ""
			(at 0 0 0)
			(layer "B.Fab")
			(effects
				(font
					(size 1.27 1.27)
				)
				(justify mirror)
			)
		)
		(duplicate_pad_numbers_are_jumpers no)
		(fp_line
			(start -0.7874 -0.4064)
			(end -0.7874 0.4064)
			(stroke
				(width 0.1524)
				(type default)
			)
			(layer "B.SilkS")
		)
		(fp_line
			(start -0.7874 0.4064)
			(end 0.7874 0.4064)
			(stroke
				(width 0.1524)
				(type default)
			)
			(layer "B.SilkS")
		)
		(fp_line
			(start 0.7874 -0.4064)
			(end -0.7874 -0.4064)
			(stroke
				(width 0.1524)
				(type default)
			)
			(layer "B.SilkS")
		)
		(fp_line
			(start 0.7874 0.4064)
			(end 0.7874 -0.4064)
			(stroke
				(width 0.1524)
				(type default)
			)
			(layer "B.SilkS")
		)
		(fp_line
			(start -0.67945 -0.3048)
			(end -0.67945 0.3048)
			(stroke
				(width 0.1)
				(type default)
			)
			(layer "B.Fab")
		)
		(fp_line
			(start -0.67945 0.3048)
			(end -0.120396 0.3048)
			(stroke
				(width 0.1)
				(type default)
			)
			(layer "B.Fab")
		)
		(fp_line
			(start -0.12065 -0.3048)
			(end -0.67945 -0.3048)
			(stroke
				(width 0.1)
				(type default)
			)
			(layer "B.Fab")
		)
		(fp_line
			(start -0.12065 -0.2794)
			(end -0.12065 -0.3048)
			(stroke
				(width 0.1)
				(type default)
			)
			(layer "B.Fab")
		)
		(fp_line
			(start -0.120396 0.2794)
			(end 0.12065 0.2794)
			(stroke
				(width 0.1)
				(type default)
			)
			(layer "B.Fab")
		)
		(fp_line
			(start -0.120396 0.3048)
			(end -0.120396 0.2794)
			(stroke
				(width 0.1)
				(type default)
			)
			(layer "B.Fab")
		)
		(fp_line
			(start 0.12065 -0.305054)
			(end 0.12065 -0.2794)
			(stroke
				(width 0.1)
				(type default)
			)
			(layer "B.Fab")
		)
		(fp_line
			(start 0.12065 -0.2794)
			(end -0.12065 -0.2794)
			(stroke
				(width 0.1)
				(type default)
			)
			(layer "B.Fab")
		)
		(fp_line
			(start 0.12065 0.2794)
			(end 0.12065 0.3048)
			(stroke
				(width 0.1)
				(type default)
			)
			(layer "B.Fab")
		)
		(fp_line
			(start 0.12065 0.3048)
			(end 0.67945 0.3048)
			(stroke
				(width 0.1)
				(type default)
			)
			(layer "B.Fab")
		)
		(fp_line
			(start 0.67945 -0.305054)
			(end 0.12065 -0.305054)
			(stroke
				(width 0.1)
				(type default)
			)
			(layer "B.Fab")
		)
		(fp_line
			(start 0.67945 0.3048)
			(end 0.67945 -0.305054)
			(stroke
				(width 0.1)
				(type default)
			)
			(layer "B.Fab")
		)
		(pad "1" smd circle
			(at 0.40005 0 180)
			(size 0 0)
			(layers "B.Cu" "B.Mask" "B.Paste")
			(net "PVDDCR_SOC_P1")
		)
		(pad "2" smd circle
			(at -0.40005 0 180)
			(size 0 0)
			(layers "B.Cu" "B.Mask" "B.Paste")
			(net "GND")
		)
	)
	(footprint ""
		(layer "B.Cu")
		(at 378.891292 -398.942052 90)
		(property "Reference" "C996"
			(at 0 0 90)
			(layer "B.SilkS")
			(hide yes)
			(effects
				(font
					(size 1.27 1.27)
				)
				(justify mirror)
			)
		)
		(property "Value" ""
			(at 0 0 90)
			(layer "B.Fab")
			(effects
				(font
					(size 1.27 1.27)
				)
				(justify mirror)
			)
		)
		(duplicate_pad_numbers_are_jumpers no)
		(fp_line
			(start 0.7874 -0.4064)
			(end -0.7874 -0.4064)
			(stroke
				(width 0.1524)
				(type default)
			)
			(layer "B.SilkS")
		)
		(fp_line
			(start -0.7874 -0.4064)
			(end -0.7874 0.4064)
			(stroke
				(width 0.1524)
				(type default)
			)
			(layer "B.SilkS")
		)
		(fp_line
			(start 0.7874 0.4064)
			(end 0.7874 -0.4064)
			(stroke
				(width 0.1524)
				(type default)
			)
			(layer "B.SilkS")
		)
		(fp_line
			(start -0.7874 0.4064)
			(end 0.7874 0.4064)
			(stroke
				(width 0.1524)
				(type default)
			)
			(layer "B.SilkS")
		)
		(fp_line
			(start 0.67945 -0.305054)
			(end 0.12065 -0.305054)
			(stroke
				(width 0.1)
				(type default)
			)
			(layer "B.Fab")
		)
		(fp_line
			(start 0.12065 -0.305054)
			(end 0.12065 -0.2794)
			(stroke
				(width 0.1)
				(type default)
			)
			(layer "B.Fab")
		)
		(fp_line
			(start -0.12065 -0.3048)
			(end -0.67945 -0.3048)
			(stroke
				(width 0.1)
				(type default)
			)
			(layer "B.Fab")
		)
		(fp_line
			(start -0.67945 -0.3048)
			(end -0.67945 0.3048)
			(stroke
				(width 0.1)
				(type default)
			)
			(layer "B.Fab")
		)
		(fp_line
			(start 0.12065 -0.2794)
			(end -0.12065 -0.2794)
			(stroke
				(width 0.1)
				(type default)
			)
			(layer "B.Fab")
		)
		(fp_line
			(start -0.12065 -0.2794)
			(end -0.12065 -0.3048)
			(stroke
				(width 0.1)
				(type default)
			)
			(layer "B.Fab")
		)
		(fp_line
			(start 0.12065 0.2794)
			(end 0.12065 0.3048)
			(stroke
				(width 0.1)
				(type default)
			)
			(layer "B.Fab")
		)
		(fp_line
			(start -0.120396 0.2794)
			(end 0.12065 0.2794)
			(stroke
				(width 0.1)
				(type default)
			)
			(layer "B.Fab")
		)
		(fp_line
			(start 0.67945 0.3048)
			(end 0.67945 -0.305054)
			(stroke
				(width 0.1)
				(type default)
			)
			(layer "B.Fab")
		)
		(fp_line
			(start 0.12065 0.3048)
			(end 0.67945 0.3048)
			(stroke
				(width 0.1)
				(type default)
			)
			(layer "B.Fab")
		)
		(fp_line
			(start -0.120396 0.3048)
			(end -0.120396 0.2794)
			(stroke
				(width 0.1)
				(type default)
			)
			(layer "B.Fab")
		)
		(fp_line
			(start -0.67945 0.3048)
			(end -0.120396 0.3048)
			(stroke
				(width 0.1)
				(type default)
			)
			(layer "B.Fab")
		)
		(pad "1" smd circle
			(at 0.40005 0 270)
			(size 0 0)
			(layers "B.Cu" "B.Mask" "B.Paste")
			(net "P1V8_CPU0_RT3_1A")
		)
		(pad "2" smd circle
			(at -0.40005 0 270)
			(size 0 0)
			(layers "B.Cu" "B.Mask" "B.Paste")
			(net "GND")
		)
	)
)
